(kicad_pcb
	(version 20260206)
	(generator "pcbnew")
	(generator_version "10.0")
	(general
		(thickness 1.6)
		(legacy_teardrops no)
	)
	(paper "A4")
	(title_block
		(title "panther-plus-userver — 13130-1b_20150205.brd")
		(comment 1 "Honey Badger (Wiwynn) / footprints 1265-1272 of 1509")
	)
	(layers
		(0 "F.Cu" signal "TOP")
		(4 "In1.Cu" signal "L2")
		(6 "In2.Cu" signal "L3")
		(8 "In3.Cu" signal "L4")
		(10 "In4.Cu" signal "L5")
		(12 "In5.Cu" signal "L6")
		(14 "In6.Cu" signal "L7")
		(16 "In7.Cu" signal "L8")
		(18 "In8.Cu" signal "L9")
		(20 "In9.Cu" signal "L10")
		(22 "In10.Cu" signal "L11")
		(2 "B.Cu" signal "BOTTOM")
		(9 "F.Adhes" user "F.Adhesive")
		(11 "B.Adhes" user "B.Adhesive")
		(13 "F.Paste" user "Package Geometry/Pastemask Top")
		(15 "B.Paste" user "Package Geometry/Pastemask Bottom")
		(5 "F.SilkS" user "Ref Des/Silkscreen Top")
		(7 "B.SilkS" user "Ref Des/Silkscreen Bottom")
		(1 "F.Mask" user "Board Geometry/Soldermask Top")
		(3 "B.Mask" user "Board Geometry/Soldermask Bottom")
		(17 "Dwgs.User" user "User.Drawings")
		(19 "Cmts.User" user "User.Comments")
		(21 "Eco1.User" user "User.Eco1")
		(23 "Eco2.User" user "User.Eco2")
		(25 "Edge.Cuts" user "Board Geometry/Outline")
		(27 "Margin" user)
		(31 "F.CrtYd" user "Package Geometry/Place Bound Top")
		(29 "B.CrtYd" user "Package Geometry/Place Bound Bottom")
		(35 "F.Fab" user "Ref Des/Assembly Top")
		(33 "B.Fab" user "Ref Des/Assembly Bottom")
	)
	(footprint ""
		(layer "B.Cu")
		(at 152.6794 -59.69)
		(property "Reference" "C331"
			(at 0 0 0)
			(layer "B.SilkS")
			(hide yes)
			(effects
				(font
					(size 1.27 1.27)
				)
				(justify mirror)
			)
		)
		(property "Value" "SCD1U16V2KX-3GP"
			(at -1.8923 -1.2065 0)
			(unlocked yes)
			(layer "B.Fab")
			(hide yes)
			(effects
				(font
					(size 1.016 1.016)
					(thickness 0.1524)
				)
				(justify mirror)
			)
		)
		(property "Device Type" "C402H22"
			(at -1.8923 -2.7305 0)
			(unlocked yes)
			(layer "B.Fab")
			(hide yes)
			(effects
				(font
					(size 1.016 1.016)
					(thickness 0.1524)
				)
				(justify mirror)
			)
		)
		(duplicate_pad_numbers_are_jumpers no)
		(fp_rect
			(start 0.381 0.7366)
			(end -0.381 -0.7366)
			(stroke
				(width 0)
				(type default)
			)
			(fill no)
			(layer "B.CrtYd")
		)
		(fp_rect
			(start 0.381 0.7366)
			(end -0.381 -0.7366)
			(stroke
				(width 0)
				(type default)
			)
			(fill no)
			(layer "B.Fab")
		)
		(pad "1" smd custom
			(at 0 -0.4572 180)
			(size 0.1143 0.1143)
			(layers "B.Cu" "B.Mask" "B.Paste")
			(net "PV_VDDR")
			(options
				(clearance outline)
				(anchor circle)
			)
			(primitives
				(gr_poly
					(pts
						(arc
							(start -0.254 0.1778)
							(mid -0.239121 0.213721)
							(end -0.2032 0.2286)
						)
						(arc
							(start 0.2032 0.2286)
							(mid 0.239121 0.213721)
							(end 0.254 0.1778)
						)
						(arc
							(start 0.254 -0.1778)
							(mid 0.239121 -0.213721)
							(end 0.2032 -0.2286)
						)
						(arc
							(start -0.2032 -0.2286)
							(mid -0.239121 -0.213721)
							(end -0.254 -0.1778)
						)
					)
					(width 0)
					(fill yes)
				)
			)
		)
		(pad "2" smd custom
			(at 0 0.4572 180)
			(size 0.1143 0.1143)
			(layers "B.Cu" "B.Mask" "B.Paste")
			(net "GND")
			(options
				(clearance outline)
				(anchor circle)
			)
			(primitives
				(gr_poly
					(pts
						(arc
							(start -0.254 0.1778)
							(mid -0.239121 0.213721)
							(end -0.2032 0.2286)
						)
						(arc
							(start 0.2032 0.2286)
							(mid 0.239121 0.213721)
							(end 0.254 0.1778)
						)
						(arc
							(start 0.254 -0.1778)
							(mid 0.239121 -0.213721)
							(end 0.2032 -0.2286)
						)
						(arc
							(start -0.2032 -0.2286)
							(mid -0.239121 -0.213721)
							(end -0.254 -0.1778)
						)
					)
					(width 0)
					(fill yes)
				)
			)
		)
	)
	(footprint ""
		(layer "B.Cu")
		(at 77.47 -13.462)
		(property "Reference" "C277"
			(at 0 0 0)
			(layer "B.SilkS")
			(hide yes)
			(effects
				(font
					(size 1.27 1.27)
				)
				(justify mirror)
			)
		)
		(property "Value" "SCD1U16V2KX-3GP"
			(at -1.1811 -2.7051 0)
			(unlocked yes)
			(layer "B.Fab")
			(hide yes)
			(effects
				(font
					(size 1.016 1.016)
					(thickness 0.1524)
				)
				(justify mirror)
			)
		)
		(property "Device Type" "C402H22"
			(at -1.1811 -4.2291 0)
			(unlocked yes)
			(layer "B.Fab")
			(hide yes)
			(effects
				(font
					(size 1.016 1.016)
					(thickness 0.1524)
				)
				(justify mirror)
			)
		)
		(duplicate_pad_numbers_are_jumpers no)
		(fp_rect
			(start 0.381 0.7366)
			(end -0.381 -0.7366)
			(stroke
				(width 0)
				(type default)
			)
			(fill no)
			(layer "B.CrtYd")
		)
		(fp_rect
			(start 0.381 0.7366)
			(end -0.381 -0.7366)
			(stroke
				(width 0)
				(type default)
			)
			(fill no)
			(layer "B.Fab")
		)
		(pad "1" smd custom
			(at 0 -0.4572 180)
			(size 0.1143 0.1143)
			(layers "B.Cu" "B.Mask" "B.Paste")
			(net "P2E_CPU_SAS_C_TX_DN1")
			(options
				(clearance outline)
				(anchor circle)
			)
			(primitives
				(gr_poly
					(pts
						(arc
							(start -0.254 0.1778)
							(mid -0.239121 0.213721)
							(end -0.2032 0.2286)
						)
						(arc
							(start 0.2032 0.2286)
							(mid 0.239121 0.213721)
							(end 0.254 0.1778)
						)
						(arc
							(start 0.254 -0.1778)
							(mid 0.239121 -0.213721)
							(end 0.2032 -0.2286)
						)
						(arc
							(start -0.2032 -0.2286)
							(mid -0.239121 -0.213721)
							(end -0.254 -0.1778)
						)
					)
					(width 0)
					(fill yes)
				)
			)
		)
		(pad "2" smd custom
			(at 0 0.4572 180)
			(size 0.1143 0.1143)
			(layers "B.Cu" "B.Mask" "B.Paste")
			(net "P2E_CPU_SAS_TX_DN1")
			(options
				(clearance outline)
				(anchor circle)
			)
			(primitives
				(gr_poly
					(pts
						(arc
							(start -0.254 0.1778)
							(mid -0.239121 0.213721)
							(end -0.2032 0.2286)
						)
						(arc
							(start 0.2032 0.2286)
							(mid 0.239121 0.213721)
							(end 0.254 0.1778)
						)
						(arc
							(start 0.254 -0.1778)
							(mid 0.239121 -0.213721)
							(end 0.2032 -0.2286)
						)
						(arc
							(start -0.2032 -0.2286)
							(mid -0.239121 -0.213721)
							(end -0.254 -0.1778)
						)
					)
					(width 0)
					(fill yes)
				)
			)
		)
	)
	(footprint ""
		(layer "B.Cu")
		(at 91.186 -35.941)
		(property "Reference" "C204"
			(at 0 0 0)
			(layer "B.SilkS")
			(hide yes)
			(effects
				(font
					(size 1.27 1.27)
				)
				(justify mirror)
			)
		)
		(property "Value" "SC1U10V2KX-1GP"
			(at -1.1811 -2.7051 0)
			(unlocked yes)
			(layer "B.Fab")
			(hide yes)
			(effects
				(font
					(size 1.016 1.016)
					(thickness 0.1524)
				)
				(justify mirror)
			)
		)
		(property "Device Type" "C402H22"
			(at -1.1811 -4.2291 0)
			(unlocked yes)
			(layer "B.Fab")
			(hide yes)
			(effects
				(font
					(size 1.016 1.016)
					(thickness 0.1524)
				)
				(justify mirror)
			)
		)
		(duplicate_pad_numbers_are_jumpers no)
		(fp_rect
			(start 0.381 0.7366)
			(end -0.381 -0.7366)
			(stroke
				(width 0)
				(type default)
			)
			(fill no)
			(layer "B.CrtYd")
		)
		(fp_rect
			(start 0.381 0.7366)
			(end -0.381 -0.7366)
			(stroke
				(width 0)
				(type default)
			)
			(fill no)
			(layer "B.Fab")
		)
		(pad "1" smd custom
			(at 0 -0.4572 180)
			(size 0.1143 0.1143)
			(layers "B.Cu" "B.Mask" "B.Paste")
			(net "P1V0_STBY")
			(options
				(clearance outline)
				(anchor circle)
			)
			(primitives
				(gr_poly
					(pts
						(arc
							(start -0.254 0.1778)
							(mid -0.239121 0.213721)
							(end -0.2032 0.2286)
						)
						(arc
							(start 0.2032 0.2286)
							(mid 0.239121 0.213721)
							(end 0.254 0.1778)
						)
						(arc
							(start 0.254 -0.1778)
							(mid 0.239121 -0.213721)
							(end 0.2032 -0.2286)
						)
						(arc
							(start -0.2032 -0.2286)
							(mid -0.239121 -0.213721)
							(end -0.254 -0.1778)
						)
					)
					(width 0)
					(fill yes)
				)
			)
		)
		(pad "2" smd custom
			(at 0 0.4572 180)
			(size 0.1143 0.1143)
			(layers "B.Cu" "B.Mask" "B.Paste")
			(net "GND")
			(options
				(clearance outline)
				(anchor circle)
			)
			(primitives
				(gr_poly
					(pts
						(arc
							(start -0.254 0.1778)
							(mid -0.239121 0.213721)
							(end -0.2032 0.2286)
						)
						(arc
							(start 0.2032 0.2286)
							(mid 0.239121 0.213721)
							(end 0.254 0.1778)
						)
						(arc
							(start 0.254 -0.1778)
							(mid 0.239121 -0.213721)
							(end 0.2032 -0.2286)
						)
						(arc
							(start -0.2032 -0.2286)
							(mid -0.239121 -0.213721)
							(end -0.254 -0.1778)
						)
					)
					(width 0)
					(fill yes)
				)
			)
		)
	)
	(footprint ""
		(layer "B.Cu")
		(at 78.4098 -26.1112 180)
		(property "Reference" "R407"
			(at 0 0 0)
			(layer "B.SilkS")
			(hide yes)
			(effects
				(font
					(size 1.27 1.27)
				)
				(justify mirror)
			)
		)
		(property "Value" "0R2J-2-GP"
			(at -1.7907 -1.1176 180)
			(unlocked yes)
			(layer "B.Fab")
			(hide yes)
			(effects
				(font
					(size 1.016 1.016)
					(thickness 0.1524)
				)
				(justify mirror)
			)
		)
		(property "Device Type" "R402H16"
			(at -1.7907 -2.6416 180)
			(unlocked yes)
			(layer "B.Fab")
			(hide yes)
			(effects
				(font
					(size 1.016 1.016)
					(thickness 0.1524)
				)
				(justify mirror)
			)
		)
		(duplicate_pad_numbers_are_jumpers no)
		(fp_rect
			(start 0.381 0.8382)
			(end -0.381 -0.8382)
			(stroke
				(width 0)
				(type default)
			)
			(fill no)
			(layer "B.CrtYd")
		)
		(fp_rect
			(start 0.381 0.8382)
			(end -0.381 -0.8382)
			(stroke
				(width 0)
				(type default)
			)
			(fill no)
			(layer "B.Fab")
		)
		(pad "1" smd custom
			(at 0 -0.4318)
			(size 0.127 0.127)
			(layers "B.Cu" "B.Mask" "B.Paste")
			(net "NGFF_PRESENT_R#")
			(options
				(clearance outline)
				(anchor circle)
			)
			(primitives
				(gr_poly
					(pts
						(arc
							(start -0.2032 0.2794)
							(mid -0.239121 0.264521)
							(end -0.254 0.2286)
						)
						(arc
							(start -0.254 -0.2286)
							(mid -0.239121 -0.264521)
							(end -0.2032 -0.2794)
						)
						(arc
							(start 0.2032 -0.2794)
							(mid 0.239121 -0.264521)
							(end 0.254 -0.2286)
						)
						(arc
							(start 0.254 0.2286)
							(mid 0.239121 0.264521)
							(end 0.2032 0.2794)
						)
					)
					(width 0)
					(fill yes)
				)
			)
		)
		(pad "2" smd custom
			(at 0 0.4318)
			(size 0.127 0.127)
			(layers "B.Cu" "B.Mask" "B.Paste")
			(net "NGFF_PRESENT#")
			(options
				(clearance outline)
				(anchor circle)
			)
			(primitives
				(gr_poly
					(pts
						(arc
							(start -0.2032 0.2794)
							(mid -0.239121 0.264521)
							(end -0.254 0.2286)
						)
						(arc
							(start -0.254 -0.2286)
							(mid -0.239121 -0.264521)
							(end -0.2032 -0.2794)
						)
						(arc
							(start 0.2032 -0.2794)
							(mid 0.239121 -0.264521)
							(end 0.254 -0.2286)
						)
						(arc
							(start 0.254 0.2286)
							(mid 0.239121 0.264521)
							(end 0.2032 0.2794)
						)
					)
					(width 0)
					(fill yes)
				)
			)
		)
	)
	(footprint ""
		(layer "B.Cu")
		(at 142.748 -47.498 -90)
		(property "Reference" "R76"
			(at 0 0 90)
			(layer "B.SilkS")
			(hide yes)
			(effects
				(font
					(size 1.27 1.27)
				)
				(justify mirror)
			)
		)
		(property "Value" "10KR2F-2-GP"
			(at -0.064008 -3.993896 270)
			(unlocked yes)
			(layer "B.Fab")
			(hide yes)
			(effects
				(font
					(size 1.016 1.016)
					(thickness 0.1524)
				)
				(justify mirror)
			)
		)
		(property "Device Type" "R402H16"
			(at -0.064008 -5.517896 270)
			(unlocked yes)
			(layer "B.Fab")
			(hide yes)
			(effects
				(font
					(size 1.016 1.016)
					(thickness 0.1524)
				)
				(justify mirror)
			)
		)
		(duplicate_pad_numbers_are_jumpers no)
		(fp_rect
			(start 0.381 0.8382)
			(end -0.381 -0.8382)
			(stroke
				(width 0)
				(type default)
			)
			(fill no)
			(layer "B.CrtYd")
		)
		(fp_rect
			(start 0.381 0.8382)
			(end -0.381 -0.8382)
			(stroke
				(width 0)
				(type default)
			)
			(fill no)
			(layer "B.Fab")
		)
		(pad "1" smd custom
			(at 0 -0.4318 90)
			(size 0.127 0.127)
			(layers "B.Cu" "B.Mask" "B.Paste")
			(net "P3V3_STBY")
			(options
				(clearance outline)
				(anchor circle)
			)
			(primitives
				(gr_poly
					(pts
						(arc
							(start -0.2032 0.2794)
							(mid -0.239121 0.264521)
							(end -0.254 0.2286)
						)
						(arc
							(start -0.254 -0.2286)
							(mid -0.239121 -0.264521)
							(end -0.2032 -0.2794)
						)
						(arc
							(start 0.2032 -0.2794)
							(mid 0.239121 -0.264521)
							(end 0.254 -0.2286)
						)
						(arc
							(start 0.254 0.2286)
							(mid 0.239121 0.264521)
							(end 0.2032 0.2794)
						)
					)
					(width 0)
					(fill yes)
				)
			)
		)
		(pad "2" smd custom
			(at 0 0.4318 90)
			(size 0.127 0.127)
			(layers "B.Cu" "B.Mask" "B.Paste")
			(net "JTAG_PLD_TMS")
			(options
				(clearance outline)
				(anchor circle)
			)
			(primitives
				(gr_poly
					(pts
						(arc
							(start -0.2032 0.2794)
							(mid -0.239121 0.264521)
							(end -0.254 0.2286)
						)
						(arc
							(start -0.254 -0.2286)
							(mid -0.239121 -0.264521)
							(end -0.2032 -0.2794)
						)
						(arc
							(start 0.2032 -0.2794)
							(mid 0.239121 -0.264521)
							(end 0.254 -0.2286)
						)
						(arc
							(start 0.254 0.2286)
							(mid 0.239121 0.264521)
							(end 0.2032 0.2794)
						)
					)
					(width 0)
					(fill yes)
				)
			)
		)
	)
	(footprint ""
		(layer "B.Cu")
		(at 51.308 -49.53 90)
		(property "Reference" "R83"
			(at 0 0 90)
			(layer "B.SilkS")
			(hide yes)
			(effects
				(font
					(size 1.27 1.27)
				)
				(justify mirror)
			)
		)
		(property "Value" "1KR2F-3-GP"
			(at -0.064008 -3.993896 90)
			(unlocked yes)
			(layer "B.Fab")
			(hide yes)
			(effects
				(font
					(size 1.016 1.016)
					(thickness 0.1524)
				)
				(justify mirror)
			)
		)
		(property "Device Type" "R402H16"
			(at -0.064008 -5.517896 90)
			(unlocked yes)
			(layer "B.Fab")
			(hide yes)
			(effects
				(font
					(size 1.016 1.016)
					(thickness 0.1524)
				)
				(justify mirror)
			)
		)
		(duplicate_pad_numbers_are_jumpers no)
		(fp_rect
			(start 0.381 0.8382)
			(end -0.381 -0.8382)
			(stroke
				(width 0)
				(type default)
			)
			(fill no)
			(layer "B.CrtYd")
		)
		(fp_rect
			(start 0.381 0.8382)
			(end -0.381 -0.8382)
			(stroke
				(width 0)
				(type default)
			)
			(fill no)
			(layer "B.Fab")
		)
		(pad "1" smd custom
			(at 0 -0.4318 270)
			(size 0.127 0.127)
			(layers "B.Cu" "B.Mask" "B.Paste")
			(net "CLKGEN_PCI_STOP#")
			(options
				(clearance outline)
				(anchor circle)
			)
			(primitives
				(gr_poly
					(pts
						(arc
							(start -0.2032 0.2794)
							(mid -0.239121 0.264521)
							(end -0.254 0.2286)
						)
						(arc
							(start -0.254 -0.2286)
							(mid -0.239121 -0.264521)
							(end -0.2032 -0.2794)
						)
						(arc
							(start 0.2032 -0.2794)
							(mid 0.239121 -0.264521)
							(end 0.254 -0.2286)
						)
						(arc
							(start 0.254 0.2286)
							(mid 0.239121 0.264521)
							(end 0.2032 0.2794)
						)
					)
					(width 0)
					(fill yes)
				)
			)
		)
		(pad "2" smd custom
			(at 0 0.4318 270)
			(size 0.127 0.127)
			(layers "B.Cu" "B.Mask" "B.Paste")
			(net "GND")
			(options
				(clearance outline)
				(anchor circle)
			)
			(primitives
				(gr_poly
					(pts
						(arc
							(start -0.2032 0.2794)
							(mid -0.239121 0.264521)
							(end -0.254 0.2286)
						)
						(arc
							(start -0.254 -0.2286)
							(mid -0.239121 -0.264521)
							(end -0.2032 -0.2794)
						)
						(arc
							(start 0.2032 -0.2794)
							(mid 0.239121 -0.264521)
							(end 0.254 -0.2286)
						)
						(arc
							(start 0.254 0.2286)
							(mid 0.239121 0.264521)
							(end 0.2032 0.2794)
						)
					)
					(width 0)
					(fill yes)
				)
			)
		)
	)
	(footprint ""
		(layer "B.Cu")
		(at 71.2216 -62.0776 -90)
		(property "Reference" "R159"
			(at 0 0 90)
			(layer "B.SilkS")
			(hide yes)
			(effects
				(font
					(size 1.27 1.27)
				)
				(justify mirror)
			)
		)
		(property "Value" "10KR2F-2-GP"
			(at -1.7907 -1.1176 270)
			(unlocked yes)
			(layer "B.Fab")
			(hide yes)
			(effects
				(font
					(size 1.016 1.016)
					(thickness 0.1524)
				)
				(justify mirror)
			)
		)
		(property "Device Type" "R402H16"
			(at -1.7907 -2.6416 270)
			(unlocked yes)
			(layer "B.Fab")
			(hide yes)
			(effects
				(font
					(size 1.016 1.016)
					(thickness 0.1524)
				)
				(justify mirror)
			)
		)
		(duplicate_pad_numbers_are_jumpers no)
		(fp_rect
			(start 0.381 0.8382)
			(end -0.381 -0.8382)
			(stroke
				(width 0)
				(type default)
			)
			(fill no)
			(layer "B.CrtYd")
		)
		(fp_rect
			(start 0.381 0.8382)
			(end -0.381 -0.8382)
			(stroke
				(width 0)
				(type default)
			)
			(fill no)
			(layer "B.Fab")
		)
		(pad "1" smd custom
			(at 0 -0.4318 90)
			(size 0.127 0.127)
			(layers "B.Cu" "B.Mask" "B.Paste")
			(net "P3V3_STBY")
			(options
				(clearance outline)
				(anchor circle)
			)
			(primitives
				(gr_poly
					(pts
						(arc
							(start -0.2032 0.2794)
							(mid -0.239121 0.264521)
							(end -0.254 0.2286)
						)
						(arc
							(start -0.254 -0.2286)
							(mid -0.239121 -0.264521)
							(end -0.2032 -0.2794)
						)
						(arc
							(start 0.2032 -0.2794)
							(mid 0.239121 -0.264521)
							(end 0.254 -0.2286)
						)
						(arc
							(start 0.254 0.2286)
							(mid 0.239121 0.264521)
							(end 0.2032 0.2794)
						)
					)
					(width 0)
					(fill yes)
				)
			)
		)
		(pad "2" smd custom
			(at 0 0.4318 90)
			(size 0.127 0.127)
			(layers "B.Cu" "B.Mask" "B.Paste")
			(net "P3V3_STBY_SENSE")
			(options
				(clearance outline)
				(anchor circle)
			)
			(primitives
				(gr_poly
					(pts
						(arc
							(start -0.2032 0.2794)
							(mid -0.239121 0.264521)
							(end -0.254 0.2286)
						)
						(arc
							(start -0.254 -0.2286)
							(mid -0.239121 -0.264521)
							(end -0.2032 -0.2794)
						)
						(arc
							(start 0.2032 -0.2794)
							(mid 0.239121 -0.264521)
							(end 0.254 -0.2286)
						)
						(arc
							(start 0.254 0.2286)
							(mid 0.239121 0.264521)
							(end 0.2032 0.2794)
						)
					)
					(width 0)
					(fill yes)
				)
			)
		)
	)
	(footprint ""
		(layer "B.Cu")
		(at 18.6944 -61.3918 90)
		(property "Reference" "PC1"
			(at 0 0 90)
			(layer "B.SilkS")
			(hide yes)
			(effects
				(font
					(size 1.27 1.27)
				)
				(justify mirror)
			)
		)
		(property "Value" "SC100P50V2JN-3GP"
			(at -1.8923 -1.2065 90)
			(unlocked yes)
			(layer "B.Fab")
			(hide yes)
			(effects
				(font
					(size 1.016 1.016)
					(thickness 0.1524)
				)
				(justify mirror)
			)
		)
		(property "Device Type" "C402H22"
			(at -1.8923 -2.7305 90)
			(unlocked yes)
			(layer "B.Fab")
			(hide yes)
			(effects
				(font
					(size 1.016 1.016)
					(thickness 0.1524)
				)
				(justify mirror)
			)
		)
		(duplicate_pad_numbers_are_jumpers no)
		(fp_rect
			(start 0.381 0.7366)
			(end -0.381 -0.7366)
			(stroke
				(width 0)
				(type default)
			)
			(fill no)
			(layer "B.CrtYd")
		)
		(fp_rect
			(start 0.381 0.7366)
			(end -0.381 -0.7366)
			(stroke
				(width 0)
				(type default)
			)
			(fill no)
			(layer "B.Fab")
		)
		(pad "1" smd custom
			(at 0 -0.4572 270)
			(size 0.1143 0.1143)
			(layers "B.Cu" "B.Mask" "B.Paste")
			(net "VR_PVNN_COMP")
			(options
				(clearance outline)
				(anchor circle)
			)
			(primitives
				(gr_poly
					(pts
						(arc
							(start -0.254 0.1778)
							(mid -0.239121 0.213721)
							(end -0.2032 0.2286)
						)
						(arc
							(start 0.2032 0.2286)
							(mid 0.239121 0.213721)
							(end 0.254 0.1778)
						)
						(arc
							(start 0.254 -0.1778)
							(mid 0.239121 -0.213721)
							(end 0.2032 -0.2286)
						)
						(arc
							(start -0.2032 -0.2286)
							(mid -0.239121 -0.213721)
							(end -0.254 -0.1778)
						)
					)
					(width 0)
					(fill yes)
				)
			)
		)
		(pad "2" smd custom
			(at 0 0.4572 270)
			(size 0.1143 0.1143)
			(layers "B.Cu" "B.Mask" "B.Paste")
			(net "VR_PVNN_FB")
			(options
				(clearance outline)
				(anchor circle)
			)
			(primitives
				(gr_poly
					(pts
						(arc
							(start -0.254 0.1778)
							(mid -0.239121 0.213721)
							(end -0.2032 0.2286)
						)
						(arc
							(start 0.2032 0.2286)
							(mid 0.239121 0.213721)
							(end 0.254 0.1778)
						)
						(arc
							(start 0.254 -0.1778)
							(mid 0.239121 -0.213721)
							(end 0.2032 -0.2286)
						)
						(arc
							(start -0.2032 -0.2286)
							(mid -0.239121 -0.213721)
							(end -0.254 -0.1778)
						)
					)
					(width 0)
					(fill yes)
				)
			)
		)
	)
)
